(kicad_pcb
	(version 20221018)
	(generator pcbnew)
	(general
    (thickness 1.7403)
  )
	(paper "A4")
	(title_block
    (title "Data Center RDIMM DDR4 Tester")
    (date "2024-09-30")
    (rev "1.2.4")
		(comment 9 "footprints 214-223 of 690")
	)
	(layers
    (0 "F.Cu" signal)
    (1 "In1.Cu" power)
    (2 "In2.Cu" signal)
    (3 "In3.Cu" power)
    (4 "In4.Cu" power)
    (5 "In5.Cu" signal)
    (6 "In6.Cu" power)
    (7 "In7.Cu" signal)
    (8 "In8.Cu" power)
    (9 "In9.Cu" signal)
    (10 "In10.Cu" power)
    (31 "B.Cu" signal)
    (32 "B.Adhes" user "B.Adhesive")
    (33 "F.Adhes" user "F.Adhesive")
    (34 "B.Paste" user)
    (35 "F.Paste" user)
    (36 "B.SilkS" user "B.Silkscreen")
    (37 "F.SilkS" user "F.Silkscreen")
    (38 "B.Mask" user)
    (39 "F.Mask" user)
    (40 "Dwgs.User" user "User.Drawings")
    (41 "Cmts.User" user "User.Comments")
    (42 "Eco1.User" user "User.Eco1")
    (43 "Eco2.User" user "User.Eco2")
    (44 "Edge.Cuts" user)
    (45 "Margin" user)
    (46 "B.CrtYd" user "B.Courtyard")
    (47 "F.CrtYd" user "F.Courtyard")
    (48 "B.Fab" user)
    (49 "F.Fab" user)
  )
	(footprint "data-center-rdimm-ddr4-tester-footprints:C_0402_1005Metric" (layer "F.Cu")
    (at 124.326328 107.320008 -90)
    (descr "Capacitor SMD 0402")
    (tags "capacitor SMD 0402")
    (property "Author" "Antmicro")
    (property "Dielectric" "")
    (property "License" "Apache-2.0")
    (property "MPN" "CC0402MRX5R5BB106")
    (property "Manufacturer" "Yaego")
    (property "Sheetfile" "supply.kicad_sch")
    (property "Sheetname" "Supply")
    (property "Val" "10u")
    (property "Voltage" "")
    (property "ki_description" " ")
    (attr smd)
    (fp_text reference "C150" (at 1.259992 -2.213672 -90) (layer "F.SilkS")
        (effects (font (size 0.7 0.7) (thickness 0.15)) (justify left bottom))
    )
    (fp_text value "C_10u_0402" (at 0 1.4 -90) (layer "F.Fab") hide
        (effects (font (size 0.7 0.7) (thickness 0.15)) (justify left bottom))
    )
    (fp_text user "Author: Antmicro" (at -0.932 4.17 -90) (layer "F.Fab") hide
        (effects (font (size 0.7 0.7) (thickness 0.15)) (justify left bottom))
    )
    (fp_text user "License: Apache-2.0" (at -0.932 5.17 -90) (layer "F.Fab") hide
        (effects (font (size 0.7 0.7) (thickness 0.15)) (justify left bottom))
    )
    (fp_text user "${REFERENCE}" (at -0.932 3.168 -90) (layer "F.Fab") hide
        (effects (font (size 0.7 0.7) (thickness 0.15)) (justify left bottom))
    )
    (fp_rect (start -0.94 -0.47) (end 0.94 0.47)
      (stroke (width 0.05) (type solid)) (fill none) (layer "F.CrtYd"))
    (fp_rect (start -0.499 -0.249) (end 0.499 0.249)
      (stroke (width 0.15) (type solid)) (fill none) (layer "F.Fab"))
    (pad "1" smd roundrect (at -0.484 0 270) (size 0.59 0.64) (layers "F.Cu" "F.Paste" "F.Mask") (roundrect_rratio 0.25)
      (net 307 "5V0_SYS") (pintype "passive"))
    (pad "2" smd roundrect (at 0.484 0 270) (size 0.59 0.64) (layers "F.Cu" "F.Paste" "F.Mask") (roundrect_rratio 0.25)
      (net 9 "GND") (pintype "passive"))
  )
	(footprint "data-center-rdimm-ddr4-tester-footprints:C_0402_1005Metric" (layer "F.Cu")
    (at 130.336328 95.085008 180)
    (descr "Capacitor SMD 0402")
    (tags "capacitor SMD 0402")
    (property "Author" "Antmicro")
    (property "Dielectric" "")
    (property "License" "Apache-2.0")
    (property "MPN" "CC0402MRX5R5BB106")
    (property "Manufacturer" "Yaego")
    (property "Sheetfile" "supply.kicad_sch")
    (property "Sheetname" "Supply")
    (property "Val" "10u")
    (property "Voltage" "")
    (property "ki_description" " ")
    (attr smd)
    (fp_text reference "C151" (at 1.456328 -1.264992 180) (layer "F.SilkS")
        (effects (font (size 0.7 0.7) (thickness 0.15)) (justify left bottom))
    )
    (fp_text value "C_10u_0402" (at 0 1.4 180) (layer "F.Fab") hide
        (effects (font (size 0.7 0.7) (thickness 0.15)) (justify left bottom))
    )
    (fp_text user "${REFERENCE}" (at -0.932 3.168 180) (layer "F.Fab") hide
        (effects (font (size 0.7 0.7) (thickness 0.15)) (justify left bottom))
    )
    (fp_text user "Author: Antmicro" (at -0.932 4.17 180) (layer "F.Fab") hide
        (effects (font (size 0.7 0.7) (thickness 0.15)) (justify left bottom))
    )
    (fp_text user "License: Apache-2.0" (at -0.932 5.17 180) (layer "F.Fab") hide
        (effects (font (size 0.7 0.7) (thickness 0.15)) (justify left bottom))
    )
    (fp_rect (start -0.94 -0.47) (end 0.94 0.47)
      (stroke (width 0.05) (type solid)) (fill none) (layer "F.CrtYd"))
    (fp_rect (start -0.499 -0.249) (end 0.499 0.249)
      (stroke (width 0.15) (type solid)) (fill none) (layer "F.Fab"))
    (pad "1" smd roundrect (at -0.484 0 180) (size 0.59 0.64) (layers "F.Cu" "F.Paste" "F.Mask") (roundrect_rratio 0.25)
      (net 307 "5V0_SYS") (pintype "passive"))
    (pad "2" smd roundrect (at 0.484 0 180) (size 0.59 0.64) (layers "F.Cu" "F.Paste" "F.Mask") (roundrect_rratio 0.25)
      (net 9 "GND") (pintype "passive"))
  )
	(footprint "data-center-rdimm-ddr4-tester-footprints:C_0402_1005Metric" (layer "F.Cu")
    (at 146.474328 121.852008 -90)
    (descr "Capacitor SMD 0402")
    (tags "capacitor SMD 0402")
    (property "Author" "Antmicro")
    (property "Dielectric" "")
    (property "License" "Apache-2.0")
    (property "MPN" "04024W226MAT2A")
    (property "Manufacturer" "AVX")
    (property "Sheetfile" "supply.kicad_sch")
    (property "Sheetname" "Supply")
    (property "Val" "22u")
    (property "Voltage" "")
    (property "ki_description" " ")
    (attr smd)
    (fp_text reference "C152" (at 1.477992 2.539328 -90) (layer "F.SilkS")
        (effects (font (size 0.7 0.7) (thickness 0.15)) (justify left bottom))
    )
    (fp_text value "C_22u_0402" (at 0 1.4 -90) (layer "F.Fab") hide
        (effects (font (size 0.7 0.7) (thickness 0.15)) (justify left bottom))
    )
    (fp_text user "${REFERENCE}" (at -0.932 3.168 -90) (layer "F.Fab") hide
        (effects (font (size 0.7 0.7) (thickness 0.15)) (justify left bottom))
    )
    (fp_text user "Author: Antmicro" (at -0.932 4.17 -90) (layer "F.Fab") hide
        (effects (font (size 0.7 0.7) (thickness 0.15)) (justify left bottom))
    )
    (fp_text user "License: Apache-2.0" (at -0.932 5.17 -90) (layer "F.Fab") hide
        (effects (font (size 0.7 0.7) (thickness 0.15)) (justify left bottom))
    )
    (fp_rect (start -0.94 -0.47) (end 0.94 0.47)
      (stroke (width 0.05) (type solid)) (fill none) (layer "F.CrtYd"))
    (fp_rect (start -0.499 -0.249) (end 0.499 0.249)
      (stroke (width 0.15) (type solid)) (fill none) (layer "F.Fab"))
    (pad "1" smd roundrect (at -0.484 0 270) (size 0.59 0.64) (layers "F.Cu" "F.Paste" "F.Mask") (roundrect_rratio 0.25)
      (net 176 "VCC1V2") (pintype "passive"))
    (pad "2" smd roundrect (at 0.484 0 270) (size 0.59 0.64) (layers "F.Cu" "F.Paste" "F.Mask") (roundrect_rratio 0.25)
      (net 9 "GND") (pintype "passive"))
  )
	(footprint "data-center-rdimm-ddr4-tester-footprints:C_0402_1005Metric" (layer "F.Cu")
    (at 147.484328 121.852008 -90)
    (descr "Capacitor SMD 0402")
    (tags "capacitor SMD 0402")
    (property "Author" "Antmicro")
    (property "Dielectric" "")
    (property "License" "Apache-2.0")
    (property "MPN" "04024W226MAT2A")
    (property "Manufacturer" "AVX")
    (property "Sheetfile" "supply.kicad_sch")
    (property "Sheetname" "Supply")
    (property "Val" "22u")
    (property "Voltage" "")
    (property "ki_description" " ")
    (attr smd)
    (fp_text reference "C155" (at 1.477992 2.539328 -90) (layer "F.SilkS")
        (effects (font (size 0.7 0.7) (thickness 0.15)) (justify left bottom))
    )
    (fp_text value "C_22u_0402" (at 0 1.4 -90) (layer "F.Fab") hide
        (effects (font (size 0.7 0.7) (thickness 0.15)) (justify left bottom))
    )
    (fp_text user "License: Apache-2.0" (at -0.932 5.17 -90) (layer "F.Fab") hide
        (effects (font (size 0.7 0.7) (thickness 0.15)) (justify left bottom))
    )
    (fp_text user "Author: Antmicro" (at -0.932 4.17 -90) (layer "F.Fab") hide
        (effects (font (size 0.7 0.7) (thickness 0.15)) (justify left bottom))
    )
    (fp_text user "${REFERENCE}" (at -0.932 3.168 -90) (layer "F.Fab") hide
        (effects (font (size 0.7 0.7) (thickness 0.15)) (justify left bottom))
    )
    (fp_rect (start -0.94 -0.47) (end 0.94 0.47)
      (stroke (width 0.05) (type solid)) (fill none) (layer "F.CrtYd"))
    (fp_rect (start -0.499 -0.249) (end 0.499 0.249)
      (stroke (width 0.15) (type solid)) (fill none) (layer "F.Fab"))
    (pad "1" smd roundrect (at -0.484 0 270) (size 0.59 0.64) (layers "F.Cu" "F.Paste" "F.Mask") (roundrect_rratio 0.25)
      (net 176 "VCC1V2") (pintype "passive"))
    (pad "2" smd roundrect (at 0.484 0 270) (size 0.59 0.64) (layers "F.Cu" "F.Paste" "F.Mask") (roundrect_rratio 0.25)
      (net 9 "GND") (pintype "passive"))
  )
	(footprint "data-center-rdimm-ddr4-tester-footprints:C_0402_1005Metric" (layer "F.Cu")
    (at 119.566328 104.990008 -90)
    (descr "Capacitor SMD 0402")
    (tags "capacitor SMD 0402")
    (property "Author" "Antmicro")
    (property "Dielectric" "X5R")
    (property "License" "Apache-2.0")
    (property "MPN" "GRM155R61H104KE14D")
    (property "Manufacturer" "Murata")
    (property "Sheetfile" "supply.kicad_sch")
    (property "Sheetname" "Supply")
    (property "Val" "100n")
    (property "Voltage" "50V")
    (property "ki_description" " ")
    (attr smd)
    (fp_text reference "C157" (at 1.219992 0.566328 -90) (layer "F.SilkS")
        (effects (font (size 0.7 0.7) (thickness 0.15)) (justify left bottom))
    )
    (fp_text value "C_100n_0402" (at 0 1.4 -90) (layer "F.Fab") hide
        (effects (font (size 0.7 0.7) (thickness 0.15)) (justify left bottom))
    )
    (fp_text user "Author: Antmicro" (at -0.932 4.17 -90) (layer "F.Fab") hide
        (effects (font (size 0.7 0.7) (thickness 0.15)) (justify left bottom))
    )
    (fp_text user "License: Apache-2.0" (at -0.932 5.17 -90) (layer "F.Fab") hide
        (effects (font (size 0.7 0.7) (thickness 0.15)) (justify left bottom))
    )
    (fp_text user "${REFERENCE}" (at -0.932 3.168 -90) (layer "F.Fab") hide
        (effects (font (size 0.7 0.7) (thickness 0.15)) (justify left bottom))
    )
    (fp_rect (start -0.94 -0.47) (end 0.94 0.47)
      (stroke (width 0.05) (type solid)) (fill none) (layer "F.CrtYd"))
    (fp_rect (start -0.499 -0.249) (end 0.499 0.249)
      (stroke (width 0.15) (type solid)) (fill none) (layer "F.Fab"))
    (pad "1" smd roundrect (at -0.484 0 270) (size 0.59 0.64) (layers "F.Cu" "F.Paste" "F.Mask") (roundrect_rratio 0.25)
      (net 49 "Net-(U9-BST)") (pintype "passive"))
    (pad "2" smd roundrect (at 0.484 0 270) (size 0.59 0.64) (layers "F.Cu" "F.Paste" "F.Mask") (roundrect_rratio 0.25)
      (net 50 "Net-(U9-SW)") (pintype "passive"))
  )
	(footprint "data-center-rdimm-ddr4-tester-footprints:C_0402_1005Metric" (layer "F.Cu")
    (at 134.536328 91.810008 90)
    (descr "Capacitor SMD 0402")
    (tags "capacitor SMD 0402")
    (property "Author" "Antmicro")
    (property "Dielectric" "X5R")
    (property "License" "Apache-2.0")
    (property "MPN" "GRM155R61H104KE14D")
    (property "Manufacturer" "Murata")
    (property "Sheetfile" "supply.kicad_sch")
    (property "Sheetname" "Supply")
    (property "Val" "100n")
    (property "Voltage" "50V")
    (property "ki_description" " ")
    (attr smd)
    (fp_text reference "C158" (at -1.659992 1.153672 90) (layer "F.SilkS")
        (effects (font (size 0.7 0.7) (thickness 0.15)) (justify left bottom))
    )
    (fp_text value "C_100n_0402" (at 0 1.4 90) (layer "F.Fab") hide
        (effects (font (size 0.7 0.7) (thickness 0.15)) (justify left bottom))
    )
    (fp_text user "Author: Antmicro" (at -0.932 4.17 90) (layer "F.Fab") hide
        (effects (font (size 0.7 0.7) (thickness 0.15)) (justify left bottom))
    )
    (fp_text user "${REFERENCE}" (at -0.932 3.168 90) (layer "F.Fab") hide
        (effects (font (size 0.7 0.7) (thickness 0.15)) (justify left bottom))
    )
    (fp_text user "License: Apache-2.0" (at -0.932 5.17 90) (layer "F.Fab") hide
        (effects (font (size 0.7 0.7) (thickness 0.15)) (justify left bottom))
    )
    (fp_rect (start -0.94 -0.47) (end 0.94 0.47)
      (stroke (width 0.05) (type solid)) (fill none) (layer "F.CrtYd"))
    (fp_rect (start -0.499 -0.249) (end 0.499 0.249)
      (stroke (width 0.15) (type solid)) (fill none) (layer "F.Fab"))
    (pad "1" smd roundrect (at -0.484 0 90) (size 0.59 0.64) (layers "F.Cu" "F.Paste" "F.Mask") (roundrect_rratio 0.25)
      (net 51 "Net-(U12-BST)") (pintype "passive"))
    (pad "2" smd roundrect (at 0.484 0 90) (size 0.59 0.64) (layers "F.Cu" "F.Paste" "F.Mask") (roundrect_rratio 0.25)
      (net 52 "Net-(U12-SW)") (pintype "passive"))
  )
	(footprint "data-center-rdimm-ddr4-tester-footprints:C_0402_1005Metric" (layer "F.Cu")
    (at 132.936328 83.610008)
    (descr "Capacitor SMD 0402")
    (tags "capacitor SMD 0402")
    (property "Author" "Antmicro")
    (property "Dielectric" "")
    (property "License" "Apache-2.0")
    (property "MPN" "04024W226MAT2A")
    (property "Manufacturer" "AVX")
    (property "Sheetfile" "supply.kicad_sch")
    (property "Sheetname" "Supply")
    (property "Val" "22u")
    (property "Voltage" "")
    (property "ki_description" " ")
    (attr smd)
    (fp_text reference "C215" (at -1.246328 -2.460008) (layer "F.SilkS")
        (effects (font (size 0.7 0.7) (thickness 0.15)) (justify left bottom))
    )
    (fp_text value "C_22u_0402" (at 0 1.4) (layer "F.Fab") hide
        (effects (font (size 0.7 0.7) (thickness 0.15)) (justify left bottom))
    )
    (fp_text user "License: Apache-2.0" (at -0.932 5.17) (layer "F.Fab") hide
        (effects (font (size 0.7 0.7) (thickness 0.15)) (justify left bottom))
    )
    (fp_text user "Author: Antmicro" (at -0.932 4.17) (layer "F.Fab") hide
        (effects (font (size 0.7 0.7) (thickness 0.15)) (justify left bottom))
    )
    (fp_text user "${REFERENCE}" (at -0.932 3.168) (layer "F.Fab") hide
        (effects (font (size 0.7 0.7) (thickness 0.15)) (justify left bottom))
    )
    (fp_rect (start -0.94 -0.47) (end 0.94 0.47)
      (stroke (width 0.05) (type solid)) (fill none) (layer "F.CrtYd"))
    (fp_rect (start -0.499 -0.249) (end 0.499 0.249)
      (stroke (width 0.15) (type solid)) (fill none) (layer "F.Fab"))
    (pad "1" smd roundrect (at -0.484 0) (size 0.59 0.64) (layers "F.Cu" "F.Paste" "F.Mask") (roundrect_rratio 0.25)
      (net 302 "VCC1V8") (pintype "passive"))
    (pad "2" smd roundrect (at 0.484 0) (size 0.59 0.64) (layers "F.Cu" "F.Paste" "F.Mask") (roundrect_rratio 0.25)
      (net 9 "GND") (pintype "passive"))
  )
	(footprint "data-center-rdimm-ddr4-tester-footprints:C_0402_1005Metric" (layer "F.Cu")
    (at 132.951328 84.610008)
    (descr "Capacitor SMD 0402")
    (tags "capacitor SMD 0402")
    (property "Author" "Antmicro")
    (property "Dielectric" "")
    (property "License" "Apache-2.0")
    (property "MPN" "04024W226MAT2A")
    (property "Manufacturer" "AVX")
    (property "Sheetfile" "supply.kicad_sch")
    (property "Sheetname" "Supply")
    (property "Val" "22u")
    (property "Voltage" "")
    (property "ki_description" " ")
    (attr smd)
    (fp_text reference "C217" (at -1.246328 -2.460008) (layer "F.SilkS")
        (effects (font (size 0.7 0.7) (thickness 0.15)) (justify left bottom))
    )
    (fp_text value "C_22u_0402" (at 0 1.4) (layer "F.Fab") hide
        (effects (font (size 0.7 0.7) (thickness 0.15)) (justify left bottom))
    )
    (fp_text user "License: Apache-2.0" (at -0.932 5.17) (layer "F.Fab") hide
        (effects (font (size 0.7 0.7) (thickness 0.15)) (justify left bottom))
    )
    (fp_text user "${REFERENCE}" (at -0.932 3.168) (layer "F.Fab") hide
        (effects (font (size 0.7 0.7) (thickness 0.15)) (justify left bottom))
    )
    (fp_text user "Author: Antmicro" (at -0.932 4.17) (layer "F.Fab") hide
        (effects (font (size 0.7 0.7) (thickness 0.15)) (justify left bottom))
    )
    (fp_rect (start -0.94 -0.47) (end 0.94 0.47)
      (stroke (width 0.05) (type solid)) (fill none) (layer "F.CrtYd"))
    (fp_rect (start -0.499 -0.249) (end 0.499 0.249)
      (stroke (width 0.15) (type solid)) (fill none) (layer "F.Fab"))
    (pad "1" smd roundrect (at -0.484 0) (size 0.59 0.64) (layers "F.Cu" "F.Paste" "F.Mask") (roundrect_rratio 0.25)
      (net 302 "VCC1V8") (pintype "passive"))
    (pad "2" smd roundrect (at 0.484 0) (size 0.59 0.64) (layers "F.Cu" "F.Paste" "F.Mask") (roundrect_rratio 0.25)
      (net 9 "GND") (pintype "passive"))
  )
	(footprint "data-center-rdimm-ddr4-tester-footprints:C_0402_1005Metric" (layer "F.Cu")
    (at 120.65 108.95 90)
    (descr "Capacitor SMD 0402")
    (tags "capacitor SMD 0402")
    (property "Author" "Antmicro")
    (property "Dielectric" "")
    (property "License" "Apache-2.0")
    (property "MPN" "04024W226MAT2A")
    (property "Manufacturer" "AVX")
    (property "Sheetfile" "supply.kicad_sch")
    (property "Sheetname" "Supply")
    (property "Val" "22u")
    (property "Voltage" "")
    (property "ki_description" " ")
    (attr smd)
    (fp_text reference "C218" (at -3.7 -1.75 180) (layer "F.SilkS")
        (effects (font (size 0.7 0.7) (thickness 0.15)) (justify left bottom))
    )
    (fp_text value "C_22u_0402" (at 0 1.4 90) (layer "F.Fab") hide
        (effects (font (size 0.7 0.7) (thickness 0.15)) (justify left bottom))
    )
    (fp_text user "Author: Antmicro" (at -0.932 4.17 90) (layer "F.Fab") hide
        (effects (font (size 0.7 0.7) (thickness 0.15)) (justify left bottom))
    )
    (fp_text user "${REFERENCE}" (at -0.932 3.168 90) (layer "F.Fab") hide
        (effects (font (size 0.7 0.7) (thickness 0.15)) (justify left bottom))
    )
    (fp_text user "License: Apache-2.0" (at -0.932 5.17 90) (layer "F.Fab") hide
        (effects (font (size 0.7 0.7) (thickness 0.15)) (justify left bottom))
    )
    (fp_rect (start -0.94 -0.47) (end 0.94 0.47)
      (stroke (width 0.05) (type solid)) (fill none) (layer "F.CrtYd"))
    (fp_rect (start -0.499 -0.249) (end 0.499 0.249)
      (stroke (width 0.15) (type solid)) (fill none) (layer "F.Fab"))
    (pad "1" smd roundrect (at -0.484 0 90) (size 0.59 0.64) (layers "F.Cu" "F.Paste" "F.Mask") (roundrect_rratio 0.25)
      (net 304 "VCC3V3") (pintype "passive"))
    (pad "2" smd roundrect (at 0.484 0 90) (size 0.59 0.64) (layers "F.Cu" "F.Paste" "F.Mask") (roundrect_rratio 0.25)
      (net 9 "GND") (pintype "passive"))
  )
	(footprint "data-center-rdimm-ddr4-tester-footprints:C_0402_1005Metric" (layer "F.Cu")
    (at 132.936328 85.610008)
    (descr "Capacitor SMD 0402")
    (tags "capacitor SMD 0402")
    (property "Author" "Antmicro")
    (property "Dielectric" "")
    (property "License" "Apache-2.0")
    (property "MPN" "C1005X6S1A105K050BC")
    (property "Manufacturer" "TDK")
    (property "Sheetfile" "supply.kicad_sch")
    (property "Sheetname" "Supply")
    (property "Val" "1u")
    (property "Voltage" "")
    (property "ki_description" " ")
    (attr smd)
    (fp_text reference "C219" (at -1.246328 -2.460008) (layer "F.SilkS")
        (effects (font (size 0.7 0.7) (thickness 0.15)) (justify left bottom))
    )
    (fp_text value "C_1u_0402" (at 0 1.4) (layer "F.Fab") hide
        (effects (font (size 0.7 0.7) (thickness 0.15)) (justify left bottom))
    )
    (fp_text user "${REFERENCE}" (at -0.932 3.168) (layer "F.Fab") hide
        (effects (font (size 0.7 0.7) (thickness 0.15)) (justify left bottom))
    )
    (fp_text user "License: Apache-2.0" (at -0.932 5.17) (layer "F.Fab") hide
        (effects (font (size 0.7 0.7) (thickness 0.15)) (justify left bottom))
    )
    (fp_text user "Author: Antmicro" (at -0.932 4.17) (layer "F.Fab") hide
        (effects (font (size 0.7 0.7) (thickness 0.15)) (justify left bottom))
    )
    (fp_rect (start -0.94 -0.47) (end 0.94 0.47)
      (stroke (width 0.05) (type solid)) (fill none) (layer "F.CrtYd"))
    (fp_rect (start -0.499 -0.249) (end 0.499 0.249)
      (stroke (width 0.15) (type solid)) (fill none) (layer "F.Fab"))
    (pad "1" smd roundrect (at -0.484 0) (size 0.59 0.64) (layers "F.Cu" "F.Paste" "F.Mask") (roundrect_rratio 0.25)
      (net 302 "VCC1V8") (pintype "passive"))
    (pad "2" smd roundrect (at 0.484 0) (size 0.59 0.64) (layers "F.Cu" "F.Paste" "F.Mask") (roundrect_rratio 0.25)
      (net 9 "GND") (pintype "passive"))
  )
)
